# T6G (Grand Teton) — schematic netlist excerpt (pin names and nets, part order shuffled) for the footprints in the layout excerpt that follows; sources: Cadence DE-HDL packaged netlist, KiCad conversion of 04192023_DAF0TMB3IC0_F0TG_MB_C_brd_V02_OCP.brd

R3215  Q_RES  0 5% EMPTY  pkg 0402LF  page 138 : A = NCSI_BMC_TXD1_R1 ; B = RMII_BMC_OCP_TXD_1
C779  Q_CAP  1UF 4V 20% X6S  pkg 0201  page 301 : A = P0V9_CPU0_RT2_2A ; B = GND
R6117  Q_RES  100 1% CHIP  pkg 0402LF  page 80 : A = HP_LVC3_OCP_V3_2_PRSNT2_PLD_N ; B = PRSNT_OCP_V3_2_N

(kicad_pcb
	(version 20260206)
	(generator "pcbnew")
	(generator_version "10.0")
	(general
		(thickness 1.6)
		(legacy_teardrops no)
	)
	(paper "A4")
	(title_block
		(title "04192023_DAF0TMB3IC0_F0TG_MB_C_brd_V02_OCP.brd")
		(comment 1 "Grand Teton / footprints 7408-7410 of 8354")
	)
	(layers
		(0 "F.Cu" signal "TOP")
		(4 "In1.Cu" signal "GND")
		(6 "In2.Cu" signal "IN1")
		(8 "In3.Cu" signal "GND1")
		(10 "In4.Cu" signal "IN2")
		(12 "In5.Cu" signal "GND2")
		(14 "In6.Cu" signal "IN3")
		(16 "In7.Cu" signal "GND3")
		(18 "In8.Cu" signal "VCC")
		(20 "In9.Cu" signal "VCC1")
		(22 "In10.Cu" signal "GND4")
		(24 "In11.Cu" signal "IN4")
		(26 "In12.Cu" signal "GND5")
		(28 "In13.Cu" signal "IN5")
		(30 "In14.Cu" signal "GND6")
		(32 "In15.Cu" signal "IN6")
		(34 "In16.Cu" signal "GND7")
		(2 "B.Cu" signal "BOTTOM")
		(9 "F.Adhes" user "F.Adhesive")
		(11 "B.Adhes" user "B.Adhesive")
		(13 "F.Paste" user "Package Geometry/Pastemask Top")
		(15 "B.Paste" user "Package Geometry/Pastemask Bottom")
		(5 "F.SilkS" user "Ref Des/Silkscreen Top")
		(7 "B.SilkS" user "Ref Des/Silkscreen Bottom")
		(1 "F.Mask" user "Board Geometry/Soldermask Top")
		(3 "B.Mask" user "Board Geometry/Soldermask Bottom")
		(17 "Dwgs.User" user "User.Drawings")
		(19 "Cmts.User" user "User.Comments")
		(21 "Eco1.User" user "User.Eco1")
		(23 "Eco2.User" user "User.Eco2")
		(25 "Edge.Cuts" user "Board Geometry/Outline")
		(27 "Margin" user)
		(31 "F.CrtYd" user "Package Geometry/Place Bound Top")
		(29 "B.CrtYd" user "Package Geometry/Place Bound Bottom")
		(35 "F.Fab" user "Ref Des/Assembly Top")
		(33 "B.Fab" user "Ref Des/Assembly Bottom")
	)
	(footprint ""
		(layer "B.Cu")
		(at 205.388972 -72.214994 180)
		(property "Reference" "R3215"
			(at 0 0 0)
			(layer "B.SilkS")
			(hide yes)
			(effects
				(font
					(size 1.27 1.27)
				)
				(justify mirror)
			)
		)
		(property "Value" ""
			(at 0 0 0)
			(layer "B.Fab")
			(effects
				(font
					(size 1.27 1.27)
				)
				(justify mirror)
			)
		)
		(duplicate_pad_numbers_are_jumpers no)
		(fp_line
			(start 0.7874 0.4064)
			(end 0.7874 -0.4064)
			(stroke
				(width 0.1524)
				(type default)
			)
			(layer "B.SilkS")
		)
		(fp_line
			(start 0.7874 -0.4064)
			(end -0.7874 -0.4064)
			(stroke
				(width 0.1524)
				(type default)
			)
			(layer "B.SilkS")
		)
		(fp_line
			(start -0.7874 0.4064)
			(end 0.7874 0.4064)
			(stroke
				(width 0.1524)
				(type default)
			)
			(layer "B.SilkS")
		)
		(fp_line
			(start -0.7874 -0.4064)
			(end -0.7874 0.4064)
			(stroke
				(width 0.1524)
				(type default)
			)
			(layer "B.SilkS")
		)
		(fp_line
			(start 0.67945 0.3048)
			(end 0.67945 -0.305054)
			(stroke
				(width 0.1)
				(type default)
			)
			(layer "B.Fab")
		)
		(fp_line
			(start 0.67945 -0.305054)
			(end 0.12065 -0.305054)
			(stroke
				(width 0.1)
				(type default)
			)
			(layer "B.Fab")
		)
		(fp_line
			(start 0.12065 0.3048)
			(end 0.67945 0.3048)
			(stroke
				(width 0.1)
				(type default)
			)
			(layer "B.Fab")
		)
		(fp_line
			(start 0.12065 0.2794)
			(end 0.12065 0.3048)
			(stroke
				(width 0.1)
				(type default)
			)
			(layer "B.Fab")
		)
		(fp_line
			(start 0.12065 -0.2794)
			(end -0.12065 -0.2794)
			(stroke
				(width 0.1)
				(type default)
			)
			(layer "B.Fab")
		)
		(fp_line
			(start 0.12065 -0.305054)
			(end 0.12065 -0.2794)
			(stroke
				(width 0.1)
				(type default)
			)
			(layer "B.Fab")
		)
		(fp_line
			(start -0.120396 0.3048)
			(end -0.120396 0.2794)
			(stroke
				(width 0.1)
				(type default)
			)
			(layer "B.Fab")
		)
		(fp_line
			(start -0.120396 0.2794)
			(end 0.12065 0.2794)
			(stroke
				(width 0.1)
				(type default)
			)
			(layer "B.Fab")
		)
		(fp_line
			(start -0.12065 -0.2794)
			(end -0.12065 -0.3048)
			(stroke
				(width 0.1)
				(type default)
			)
			(layer "B.Fab")
		)
		(fp_line
			(start -0.12065 -0.3048)
			(end -0.67945 -0.3048)
			(stroke
				(width 0.1)
				(type default)
			)
			(layer "B.Fab")
		)
		(fp_line
			(start -0.67945 0.3048)
			(end -0.120396 0.3048)
			(stroke
				(width 0.1)
				(type default)
			)
			(layer "B.Fab")
		)
		(fp_line
			(start -0.67945 -0.3048)
			(end -0.67945 0.3048)
			(stroke
				(width 0.1)
				(type default)
			)
			(layer "B.Fab")
		)
		(pad "1" smd circle
			(at 0.40005 0)
			(size 0 0)
			(layers "B.Cu" "B.Mask" "B.Paste")
			(net "NCSI_BMC_TXD1_R1")
		)
		(pad "2" smd circle
			(at -0.40005 0)
			(size 0 0)
			(layers "B.Cu" "B.Mask" "B.Paste")
			(net "RMII_BMC_OCP_TXD_1")
		)
	)
	(footprint ""
		(layer "B.Cu")
		(at 402.800566 -393.88288 -90)
		(property "Reference" "C779"
			(at 0 0 90)
			(layer "B.SilkS")
			(hide yes)
			(effects
				(font
					(size 1.27 1.27)
				)
				(justify mirror)
			)
		)
		(property "Value" ""
			(at 0 0 90)
			(layer "B.Fab")
			(effects
				(font
					(size 1.27 1.27)
				)
				(justify mirror)
			)
		)
		(duplicate_pad_numbers_are_jumpers no)
		(fp_line
			(start -0.299974 0.150114)
			(end 0.299974 0.150114)
			(stroke
				(width 0.1)
				(type default)
			)
			(layer "B.Fab")
		)
		(fp_line
			(start 0.299974 0.150114)
			(end 0.299974 -0.150114)
			(stroke
				(width 0.1)
				(type default)
			)
			(layer "B.Fab")
		)
		(fp_line
			(start -0.299974 -0.150114)
			(end -0.299974 0.150114)
			(stroke
				(width 0.1)
				(type default)
			)
			(layer "B.Fab")
		)
		(fp_line
			(start 0.299974 -0.150114)
			(end -0.299974 -0.150114)
			(stroke
				(width 0.1)
				(type default)
			)
			(layer "B.Fab")
		)
		(pad "1" smd rect
			(at 0.2667 0 90)
			(size 0.3048 0.381)
			(layers "B.Cu" "B.Mask" "B.Paste")
			(net "P0V9_CPU0_RT2_2A")
		)
		(pad "2" smd rect
			(at -0.2667 0 90)
			(size 0.3048 0.381)
			(layers "B.Cu" "B.Mask" "B.Paste")
			(net "GND")
		)
	)
	(footprint ""
		(layer "B.Cu")
		(at 171.20235 -120.233948 180)
		(property "Reference" "R6117"
			(at 0 0 0)
			(layer "B.SilkS")
			(hide yes)
			(effects
				(font
					(size 1.27 1.27)
				)
				(justify mirror)
			)
		)
		(property "Value" ""
			(at 0 0 0)
			(layer "B.Fab")
			(effects
				(font
					(size 1.27 1.27)
				)
				(justify mirror)
			)
		)
		(duplicate_pad_numbers_are_jumpers no)
		(fp_line
			(start 0.7874 0.4064)
			(end 0.7874 -0.4064)
			(stroke
				(width 0.1524)
				(type default)
			)
			(layer "B.SilkS")
		)
		(fp_line
			(start 0.7874 -0.4064)
			(end -0.7874 -0.4064)
			(stroke
				(width 0.1524)
				(type default)
			)
			(layer "B.SilkS")
		)
		(fp_line
			(start -0.7874 0.4064)
			(end 0.7874 0.4064)
			(stroke
				(width 0.1524)
				(type default)
			)
			(layer "B.SilkS")
		)
		(fp_line
			(start -0.7874 -0.4064)
			(end -0.7874 0.4064)
			(stroke
				(width 0.1524)
				(type default)
			)
			(layer "B.SilkS")
		)
		(fp_line
			(start 0.67945 0.3048)
			(end 0.67945 -0.305054)
			(stroke
				(width 0.1)
				(type default)
			)
			(layer "B.Fab")
		)
		(fp_line
			(start 0.67945 -0.305054)
			(end 0.12065 -0.305054)
			(stroke
				(width 0.1)
				(type default)
			)
			(layer "B.Fab")
		)
		(fp_line
			(start 0.12065 0.3048)
			(end 0.67945 0.3048)
			(stroke
				(width 0.1)
				(type default)
			)
			(layer "B.Fab")
		)
		(fp_line
			(start 0.12065 0.2794)
			(end 0.12065 0.3048)
			(stroke
				(width 0.1)
				(type default)
			)
			(layer "B.Fab")
		)
		(fp_line
			(start 0.12065 -0.2794)
			(end -0.12065 -0.2794)
			(stroke
				(width 0.1)
				(type default)
			)
			(layer "B.Fab")
		)
		(fp_line
			(start 0.12065 -0.305054)
			(end 0.12065 -0.2794)
			(stroke
				(width 0.1)
				(type default)
			)
			(layer "B.Fab")
		)
		(fp_line
			(start -0.120396 0.3048)
			(end -0.120396 0.2794)
			(stroke
				(width 0.1)
				(type default)
			)
			(layer "B.Fab")
		)
		(fp_line
			(start -0.120396 0.2794)
			(end 0.12065 0.2794)
			(stroke
				(width 0.1)
				(type default)
			)
			(layer "B.Fab")
		)
		(fp_line
			(start -0.12065 -0.2794)
			(end -0.12065 -0.3048)
			(stroke
				(width 0.1)
				(type default)
			)
			(layer "B.Fab")
		)
		(fp_line
			(start -0.12065 -0.3048)
			(end -0.67945 -0.3048)
			(stroke
				(width 0.1)
				(type default)
			)
			(layer "B.Fab")
		)
		(fp_line
			(start -0.67945 0.3048)
			(end -0.120396 0.3048)
			(stroke
				(width 0.1)
				(type default)
			)
			(layer "B.Fab")
		)
		(fp_line
			(start -0.67945 -0.3048)
			(end -0.67945 0.3048)
			(stroke
				(width 0.1)
				(type default)
			)
			(layer "B.Fab")
		)
		(pad "1" smd circle
			(at 0.40005 0)
			(size 0 0)
			(layers "B.Cu" "B.Mask" "B.Paste")
			(net "HP_LVC3_OCP_V3_2_PRSNT2_PLD_N")
		)
		(pad "2" smd circle
			(at -0.40005 0)
			(size 0 0)
			(layers "B.Cu" "B.Mask" "B.Paste")
			(net "PRSNT_OCP_V3_2_N")
		)
	)
)
